(kicad_pcb
	(version 20260206)
	(generator "pcbnew")
	(generator_version "10.0")
	(general
		(thickness 1.6)
		(legacy_teardrops no)
	)
	(paper "A4")
	(title_block
		(title "04192023_DAF0TMB3IC0_F0TG_MB_C_brd_V02_OCP.brd")
		(comment 1 "Grand Teton / footprint 2783 of 8354 (U26), pads 110-218 of 6102")
	)
	(layers
		(0 "F.Cu" signal "TOP")
		(4 "In1.Cu" signal "GND")
		(6 "In2.Cu" signal "IN1")
		(8 "In3.Cu" signal "GND1")
		(10 "In4.Cu" signal "IN2")
		(12 "In5.Cu" signal "GND2")
		(14 "In6.Cu" signal "IN3")
		(16 "In7.Cu" signal "GND3")
		(18 "In8.Cu" signal "VCC")
		(20 "In9.Cu" signal "VCC1")
		(22 "In10.Cu" signal "GND4")
		(24 "In11.Cu" signal "IN4")
		(26 "In12.Cu" signal "GND5")
		(28 "In13.Cu" signal "IN5")
		(30 "In14.Cu" signal "GND6")
		(32 "In15.Cu" signal "IN6")
		(34 "In16.Cu" signal "GND7")
		(2 "B.Cu" signal "BOTTOM")
		(9 "F.Adhes" user "F.Adhesive")
		(11 "B.Adhes" user "B.Adhesive")
		(13 "F.Paste" user "Package Geometry/Pastemask Top")
		(15 "B.Paste" user "Package Geometry/Pastemask Bottom")
		(5 "F.SilkS" user "Ref Des/Silkscreen Top")
		(7 "B.SilkS" user "Ref Des/Silkscreen Bottom")
		(1 "F.Mask" user "Board Geometry/Soldermask Top")
		(3 "B.Mask" user "Board Geometry/Soldermask Bottom")
		(17 "Dwgs.User" user "User.Drawings")
		(19 "Cmts.User" user "User.Comments")
		(21 "Eco1.User" user "User.Eco1")
		(23 "Eco2.User" user "User.Eco2")
		(25 "Edge.Cuts" user "Board Geometry/Outline")
		(27 "Margin" user)
		(31 "F.CrtYd" user "Package Geometry/Place Bound Top")
		(29 "B.CrtYd" user "Package Geometry/Place Bound Bottom")
		(35 "F.Fab" user "Ref Des/Assembly Top")
		(33 "B.Fab" user "Ref Des/Assembly Bottom")
	)
	(footprint ""
		(layer "F.Cu")
		(at 111.927894 -258.880356 180)
		(property "Reference" "U26"
			(at -45.05579 -61.794136 0)
			(unlocked yes)
			(layer "F.SilkS")
			(effects
				(font
					(size 0.7874 0.5842)
					(thickness 0.1524)
				)
			)
		)
		(property "Value" ""
			(at 0 0 180)
			(layer "F.Fab")
			(effects
				(font
					(size 1.27 1.27)
				)
			)
		)
		(duplicate_pad_numbers_are_jumpers no)
		(pad "AA51" smd circle
			(at 11.8999 -20.610068 180)
			(size 0.450088 0.450088)
			(layers "F.Cu" "F.Mask" "F.Paste")
			(net "TP_CPU1_TEST5_CCD0")
		)
		(pad "AA52" smd circle
			(at 12.839954 -20.610068 180)
			(size 0.450088 0.450088)
			(layers "F.Cu" "F.Mask" "F.Paste")
			(net "TP_CPU1_TEST4_CCD4")
		)
		(pad "AA53" smd circle
			(at 13.780008 -20.610068 180)
			(size 0.450088 0.450088)
			(layers "F.Cu" "F.Mask" "F.Paste")
			(net "TP_CPU1_TEST5_CCD4")
		)
		(pad "AA54" smd circle
			(at 14.720062 -20.610068 180)
			(size 0.450088 0.450088)
			(layers "F.Cu" "F.Mask" "F.Paste")
			(net "PVDDIO_P1")
		)
		(pad "AA55" smd circle
			(at 15.660116 -20.610068 180)
			(size 0.450088 0.450088)
			(layers "F.Cu" "F.Mask" "F.Paste")
			(net "M_C_CPU1_SA_DQS_DP<7>")
		)
		(pad "AA56" smd circle
			(at 16.599916 -20.610068 180)
			(size 0.450088 0.450088)
			(layers "F.Cu" "F.Mask" "F.Paste")
			(net "GND")
		)
		(pad "AA57" smd circle
			(at 17.53997 -20.610068 180)
			(size 0.450088 0.450088)
			(layers "F.Cu" "F.Mask" "F.Paste")
			(net "M_C_CPU1_SA_DQ<20>")
		)
		(pad "AA58" smd circle
			(at 18.480024 -20.610068 180)
			(size 0.450088 0.450088)
			(layers "F.Cu" "F.Mask" "F.Paste")
			(net "GND")
		)
		(pad "AA59" smd circle
			(at 19.420078 -20.610068 180)
			(size 0.450088 0.450088)
			(layers "F.Cu" "F.Mask" "F.Paste")
			(net "M_D_CPU1_SA_DQS_DP<7>")
		)
		(pad "AA60" smd circle
			(at 20.359878 -20.610068 180)
			(size 0.450088 0.450088)
			(layers "F.Cu" "F.Mask" "F.Paste")
			(net "M_D_CPU1_SA_DQ<20>")
		)
		(pad "AA61" smd circle
			(at 21.299932 -20.610068 180)
			(size 0.450088 0.450088)
			(layers "F.Cu" "F.Mask" "F.Paste")
			(net "GND")
		)
		(pad "AA62" smd circle
			(at 22.239986 -20.610068 180)
			(size 0.450088 0.450088)
			(layers "F.Cu" "F.Mask" "F.Paste")
			(net "M_B_CPU1_SA_DQS_DP<7>")
		)
		(pad "AA63" smd circle
			(at 23.18004 -20.610068 180)
			(size 0.450088 0.450088)
			(layers "F.Cu" "F.Mask" "F.Paste")
			(net "GND")
		)
		(pad "AA64" smd circle
			(at 24.120094 -20.610068 180)
			(size 0.450088 0.450088)
			(layers "F.Cu" "F.Mask" "F.Paste")
			(net "M_B_CPU1_SA_DQ<20>")
		)
		(pad "AA65" smd circle
			(at 25.059894 -20.610068 180)
			(size 0.450088 0.450088)
			(layers "F.Cu" "F.Mask" "F.Paste")
			(net "GND")
		)
		(pad "AA66" smd circle
			(at 25.999948 -20.610068 180)
			(size 0.450088 0.450088)
			(layers "F.Cu" "F.Mask" "F.Paste")
			(net "M_F_CPU1_SA_DQS_DP<7>")
		)
		(pad "AA67" smd circle
			(at 26.940002 -20.610068 180)
			(size 0.450088 0.450088)
			(layers "F.Cu" "F.Mask" "F.Paste")
			(net "M_F_CPU1_SA_DQ<20>")
		)
		(pad "AA68" smd circle
			(at 27.880056 -20.610068 180)
			(size 0.450088 0.450088)
			(layers "F.Cu" "F.Mask" "F.Paste")
			(net "GND")
		)
		(pad "AA69" smd circle
			(at 28.82011 -20.610068 180)
			(size 0.450088 0.450088)
			(layers "F.Cu" "F.Mask" "F.Paste")
			(net "M_E_CPU1_SA_DQS_DP<7>")
		)
		(pad "AA70" smd circle
			(at 29.75991 -20.610068 180)
			(size 0.450088 0.450088)
			(layers "F.Cu" "F.Mask" "F.Paste")
			(net "GND")
		)
		(pad "AA71" smd circle
			(at 30.699964 -20.610068 180)
			(size 0.450088 0.450088)
			(layers "F.Cu" "F.Mask" "F.Paste")
			(net "M_E_CPU1_SA_DQ<20>")
		)
		(pad "AA72" smd circle
			(at 31.640018 -20.610068 180)
			(size 0.450088 0.450088)
			(layers "F.Cu" "F.Mask" "F.Paste")
			(net "GND")
		)
		(pad "AA73" smd circle
			(at 32.580072 -20.610068 180)
			(size 0.450088 0.450088)
			(layers "F.Cu" "F.Mask" "F.Paste")
			(net "M_A_CPU1_SA_DQS_DP<7>")
		)
		(pad "AA74" smd circle
			(at 33.519872 -20.610068 180)
			(size 0.450088 0.450088)
			(layers "F.Cu" "F.Mask" "F.Paste")
			(net "M_A_CPU1_SA_DQ<20>")
		)
		(pad "AA75" smd circle
			(at 34.459926 -20.610068 180)
			(size 0.450088 0.450088)
			(layers "F.Cu" "F.Mask" "F.Paste")
			(net "GND")
		)
		(pad "AB2" smd circle
			(at -33.690052 -19.800062 180)
			(size 0.450088 0.450088)
			(layers "F.Cu" "F.Mask" "F.Paste")
			(net "M_G_CPU1_SA_DQ<22>")
		)
		(pad "AB3" smd circle
			(at -32.749998 -19.800062 180)
			(size 0.450088 0.450088)
			(layers "F.Cu" "F.Mask" "F.Paste")
			(net "GND")
		)
		(pad "AB4" smd circle
			(at -31.809944 -19.800062 180)
			(size 0.450088 0.450088)
			(layers "F.Cu" "F.Mask" "F.Paste")
			(net "M_G_CPU1_SA_DQ<21>")
		)
		(pad "AB5" smd circle
			(at -30.86989 -19.800062 180)
			(size 0.450088 0.450088)
			(layers "F.Cu" "F.Mask" "F.Paste")
			(net "GND")
		)
		(pad "AB6" smd circle
			(at -29.93009 -19.800062 180)
			(size 0.450088 0.450088)
			(layers "F.Cu" "F.Mask" "F.Paste")
			(net "M_K_CPU1_SA_DQ<22>")
		)
		(pad "AB7" smd circle
			(at -28.990036 -19.800062 180)
			(size 0.450088 0.450088)
			(layers "F.Cu" "F.Mask" "F.Paste")
			(net "M_K_CPU1_SA_DQ<21>")
		)
		(pad "AB8" smd circle
			(at -28.049982 -19.800062 180)
			(size 0.450088 0.450088)
			(layers "F.Cu" "F.Mask" "F.Paste")
			(net "GND")
		)
		(pad "AB9" smd circle
			(at -27.109928 -19.800062 180)
			(size 0.450088 0.450088)
			(layers "F.Cu" "F.Mask" "F.Paste")
			(net "M_L_CPU1_SA_DQ<22>")
		)
		(pad "AB10" smd circle
			(at -26.170128 -19.800062 180)
			(size 0.450088 0.450088)
			(layers "F.Cu" "F.Mask" "F.Paste")
			(net "GND")
		)
		(pad "AB11" smd circle
			(at -25.230074 -19.800062 180)
			(size 0.450088 0.450088)
			(layers "F.Cu" "F.Mask" "F.Paste")
			(net "M_L_CPU1_SA_DQ<21>")
		)
		(pad "AB12" smd circle
			(at -24.29002 -19.800062 180)
			(size 0.450088 0.450088)
			(layers "F.Cu" "F.Mask" "F.Paste")
			(net "GND")
		)
		(pad "AB13" smd circle
			(at -23.349966 -19.800062 180)
			(size 0.450088 0.450088)
			(layers "F.Cu" "F.Mask" "F.Paste")
			(net "M_H_CPU1_SA_DQ<22>")
		)
		(pad "AB14" smd circle
			(at -22.409912 -19.800062 180)
			(size 0.450088 0.450088)
			(layers "F.Cu" "F.Mask" "F.Paste")
			(net "M_H_CPU1_SA_DQ<21>")
		)
		(pad "AB15" smd circle
			(at -21.470112 -19.800062 180)
			(size 0.450088 0.450088)
			(layers "F.Cu" "F.Mask" "F.Paste")
			(net "GND")
		)
		(pad "AB16" smd circle
			(at -20.530058 -19.800062 180)
			(size 0.450088 0.450088)
			(layers "F.Cu" "F.Mask" "F.Paste")
			(net "M_J_CPU1_SA_DQ<22>")
		)
		(pad "AB17" smd circle
			(at -19.590004 -19.800062 180)
			(size 0.450088 0.450088)
			(layers "F.Cu" "F.Mask" "F.Paste")
			(net "GND")
		)
		(pad "AB18" smd circle
			(at -18.64995 -19.800062 180)
			(size 0.450088 0.450088)
			(layers "F.Cu" "F.Mask" "F.Paste")
			(net "M_J_CPU1_SA_DQ<21>")
		)
		(pad "AB19" smd circle
			(at -17.709896 -19.800062 180)
			(size 0.450088 0.450088)
			(layers "F.Cu" "F.Mask" "F.Paste")
			(net "GND")
		)
		(pad "AB20" smd circle
			(at -16.770096 -19.800062 180)
			(size 0.450088 0.450088)
			(layers "F.Cu" "F.Mask" "F.Paste")
			(net "M_I_CPU1_SA_DQ<22>")
		)
		(pad "AB21" smd circle
			(at -15.830042 -19.800062 180)
			(size 0.450088 0.450088)
			(layers "F.Cu" "F.Mask" "F.Paste")
			(net "M_I_CPU1_SA_DQ<21>")
		)
		(pad "AB22" smd circle
			(at -14.889988 -19.800062 180)
			(size 0.450088 0.450088)
			(layers "F.Cu" "F.Mask" "F.Paste")
			(net "GND")
		)
		(pad "AB23" smd circle
			(at -13.949934 -19.800062 180)
			(size 0.450088 0.450088)
			(layers "F.Cu" "F.Mask" "F.Paste")
			(net "PVDDCR_CPU0_P1")
		)
		(pad "AB24" smd circle
			(at -13.00988 -19.800062 180)
			(size 0.450088 0.450088)
			(layers "F.Cu" "F.Mask" "F.Paste")
			(net "PVDDCR_CPU0_P1")
		)
		(pad "AB25" smd circle
			(at -12.07008 -19.800062 180)
			(size 0.450088 0.450088)
			(layers "F.Cu" "F.Mask" "F.Paste")
			(net "GND")
		)
		(pad "AB26" smd circle
			(at -11.130026 -19.800062 180)
			(size 0.450088 0.450088)
			(layers "F.Cu" "F.Mask" "F.Paste")
			(net "PVDDCR_CPU0_P1")
		)
		(pad "AB27" smd circle
			(at -10.189972 -19.800062 180)
			(size 0.450088 0.450088)
			(layers "F.Cu" "F.Mask" "F.Paste")
			(net "PVDDCR_CPU0_P1")
		)
		(pad "AB28" smd circle
			(at -9.249918 -19.800062 180)
			(size 0.450088 0.450088)
			(layers "F.Cu" "F.Mask" "F.Paste")
			(net "GND")
		)
		(pad "AB29" smd circle
			(at -8.310118 -19.800062 180)
			(size 0.450088 0.450088)
			(layers "F.Cu" "F.Mask" "F.Paste")
			(net "PVDDCR_CPU0_P1")
		)
		(pad "AB30" smd circle
			(at -7.370064 -19.800062 180)
			(size 0.450088 0.450088)
			(layers "F.Cu" "F.Mask" "F.Paste")
			(net "PVDDCR_CPU0_P1")
		)
		(pad "AB31" smd circle
			(at -6.43001 -19.800062 180)
			(size 0.450088 0.450088)
			(layers "F.Cu" "F.Mask" "F.Paste")
			(net "GND")
		)
		(pad "AB32" smd circle
			(at -5.489956 -19.800062 180)
			(size 0.450088 0.450088)
			(layers "F.Cu" "F.Mask" "F.Paste")
			(net "PVDDCR_CPU0_P1")
		)
		(pad "AB33" smd circle
			(at -4.549902 -19.800062 180)
			(size 0.450088 0.450088)
			(layers "F.Cu" "F.Mask" "F.Paste")
			(net "PVDDCR_CPU0_P1")
		)
		(pad "AB34" smd circle
			(at -3.610102 -19.800062 180)
			(size 0.450088 0.450088)
			(layers "F.Cu" "F.Mask" "F.Paste")
			(net "GND")
		)
		(pad "AB35" smd circle
			(at -2.670048 -19.800062 180)
			(size 0.450088 0.450088)
			(layers "F.Cu" "F.Mask" "F.Paste")
			(net "GMI_CPU0_G0_CPU1_G2_TX_DN<2>")
		)
		(pad "AB36" smd circle
			(at -1.729994 -19.800062 180)
			(size 0.450088 0.450088)
			(layers "F.Cu" "F.Mask" "F.Paste")
			(net "GMI_CPU0_G0_CPU1_G2_TX_DP<2>")
		)
		(pad "AB37" smd circle
			(at -0.78994 -19.800062 180)
			(size 0.450088 0.450088)
			(layers "F.Cu" "F.Mask" "F.Paste")
			(net "GND")
		)
		(pad "AB39" smd circle
			(at 1.089914 -19.800062 180)
			(size 0.450088 0.450088)
			(layers "F.Cu" "F.Mask" "F.Paste")
			(net "GND")
		)
		(pad "AB40" smd circle
			(at 2.029968 -19.800062 180)
			(size 0.450088 0.450088)
			(layers "F.Cu" "F.Mask" "F.Paste")
			(net "GMI_CPU1_G0_CPU0_G2_TX_DP<13>")
		)
		(pad "AB41" smd circle
			(at 2.970022 -19.800062 180)
			(size 0.450088 0.450088)
			(layers "F.Cu" "F.Mask" "F.Paste")
			(net "GMI_CPU1_G0_CPU0_G2_TX_DN<13>")
		)
		(pad "AB42" smd circle
			(at 3.910076 -19.800062 180)
			(size 0.450088 0.450088)
			(layers "F.Cu" "F.Mask" "F.Paste")
			(net "GND")
		)
		(pad "AB43" smd circle
			(at 4.849876 -19.800062 180)
			(size 0.450088 0.450088)
			(layers "F.Cu" "F.Mask" "F.Paste")
			(net "PVDDCR_CPU0_P1")
		)
		(pad "AB44" smd circle
			(at 5.78993 -19.800062 180)
			(size 0.450088 0.450088)
			(layers "F.Cu" "F.Mask" "F.Paste")
			(net "PVDDCR_CPU0_P1")
		)
		(pad "AB45" smd circle
			(at 6.729984 -19.800062 180)
			(size 0.450088 0.450088)
			(layers "F.Cu" "F.Mask" "F.Paste")
			(net "GND")
		)
		(pad "AB46" smd circle
			(at 7.670038 -19.800062 180)
			(size 0.450088 0.450088)
			(layers "F.Cu" "F.Mask" "F.Paste")
			(net "PVDDCR_CPU0_P1")
		)
		(pad "AB47" smd circle
			(at 8.610092 -19.800062 180)
			(size 0.450088 0.450088)
			(layers "F.Cu" "F.Mask" "F.Paste")
			(net "PVDDCR_CPU0_P1")
		)
		(pad "AB48" smd circle
			(at 9.549892 -19.800062 180)
			(size 0.450088 0.450088)
			(layers "F.Cu" "F.Mask" "F.Paste")
			(net "GND")
		)
		(pad "AB49" smd circle
			(at 10.489946 -19.800062 180)
			(size 0.450088 0.450088)
			(layers "F.Cu" "F.Mask" "F.Paste")
			(net "PVDDCR_CPU0_P1")
		)
		(pad "AB50" smd circle
			(at 11.43 -19.800062 180)
			(size 0.450088 0.450088)
			(layers "F.Cu" "F.Mask" "F.Paste")
			(net "PVDDCR_CPU0_P1")
		)
		(pad "AB51" smd circle
			(at 12.370054 -19.800062 180)
			(size 0.450088 0.450088)
			(layers "F.Cu" "F.Mask" "F.Paste")
			(net "GND")
		)
		(pad "AB52" smd circle
			(at 13.310108 -19.800062 180)
			(size 0.450088 0.450088)
			(layers "F.Cu" "F.Mask" "F.Paste")
			(net "PVDDCR_CPU0_P1")
		)
		(pad "AB53" smd circle
			(at 14.249908 -19.800062 180)
			(size 0.450088 0.450088)
			(layers "F.Cu" "F.Mask" "F.Paste")
			(net "PVDDCR_CPU0_P1")
		)
		(pad "AB54" smd circle
			(at 15.189962 -19.800062 180)
			(size 0.450088 0.450088)
			(layers "F.Cu" "F.Mask" "F.Paste")
			(net "GND")
		)
		(pad "AB55" smd circle
			(at 16.130016 -19.800062 180)
			(size 0.450088 0.450088)
			(layers "F.Cu" "F.Mask" "F.Paste")
			(net "M_C_CPU1_SA_DQ<21>")
		)
		(pad "AB56" smd circle
			(at 17.07007 -19.800062 180)
			(size 0.450088 0.450088)
			(layers "F.Cu" "F.Mask" "F.Paste")
			(net "M_C_CPU1_SA_DQ<22>")
		)
		(pad "AB57" smd circle
			(at 18.010124 -19.800062 180)
			(size 0.450088 0.450088)
			(layers "F.Cu" "F.Mask" "F.Paste")
			(net "GND")
		)
		(pad "AB58" smd circle
			(at 18.949924 -19.800062 180)
			(size 0.450088 0.450088)
			(layers "F.Cu" "F.Mask" "F.Paste")
			(net "M_D_CPU1_SA_DQ<21>")
		)
		(pad "AB59" smd circle
			(at 19.889978 -19.800062 180)
			(size 0.450088 0.450088)
			(layers "F.Cu" "F.Mask" "F.Paste")
			(net "GND")
		)
		(pad "AB60" smd circle
			(at 20.830032 -19.800062 180)
			(size 0.450088 0.450088)
			(layers "F.Cu" "F.Mask" "F.Paste")
			(net "M_D_CPU1_SA_DQ<22>")
		)
		(pad "AB61" smd circle
			(at 21.770086 -19.800062 180)
			(size 0.450088 0.450088)
			(layers "F.Cu" "F.Mask" "F.Paste")
			(net "GND")
		)
		(pad "AB62" smd circle
			(at 22.709886 -19.800062 180)
			(size 0.450088 0.450088)
			(layers "F.Cu" "F.Mask" "F.Paste")
			(net "M_B_CPU1_SA_DQ<21>")
		)
		(pad "AB63" smd circle
			(at 23.64994 -19.800062 180)
			(size 0.450088 0.450088)
			(layers "F.Cu" "F.Mask" "F.Paste")
			(net "M_B_CPU1_SA_DQ<22>")
		)
		(pad "AB64" smd circle
			(at 24.589994 -19.800062 180)
			(size 0.450088 0.450088)
			(layers "F.Cu" "F.Mask" "F.Paste")
			(net "GND")
		)
		(pad "AB65" smd circle
			(at 25.530048 -19.800062 180)
			(size 0.450088 0.450088)
			(layers "F.Cu" "F.Mask" "F.Paste")
			(net "M_F_CPU1_SA_DQ<21>")
		)
		(pad "AB66" smd circle
			(at 26.470102 -19.800062 180)
			(size 0.450088 0.450088)
			(layers "F.Cu" "F.Mask" "F.Paste")
			(net "GND")
		)
		(pad "AB67" smd circle
			(at 27.409902 -19.800062 180)
			(size 0.450088 0.450088)
			(layers "F.Cu" "F.Mask" "F.Paste")
			(net "M_F_CPU1_SA_DQ<22>")
		)
		(pad "AB68" smd circle
			(at 28.349956 -19.800062 180)
			(size 0.450088 0.450088)
			(layers "F.Cu" "F.Mask" "F.Paste")
			(net "GND")
		)
		(pad "AB69" smd circle
			(at 29.29001 -19.800062 180)
			(size 0.450088 0.450088)
			(layers "F.Cu" "F.Mask" "F.Paste")
			(net "M_E_CPU1_SA_DQ<21>")
		)
		(pad "AB70" smd circle
			(at 30.230064 -19.800062 180)
			(size 0.450088 0.450088)
			(layers "F.Cu" "F.Mask" "F.Paste")
			(net "M_E_CPU1_SA_DQ<22>")
		)
		(pad "AB71" smd circle
			(at 31.170118 -19.800062 180)
			(size 0.450088 0.450088)
			(layers "F.Cu" "F.Mask" "F.Paste")
			(net "GND")
		)
		(pad "AB72" smd circle
			(at 32.109918 -19.800062 180)
			(size 0.450088 0.450088)
			(layers "F.Cu" "F.Mask" "F.Paste")
			(net "M_A_CPU1_SA_DQ<21>")
		)
		(pad "AB73" smd circle
			(at 33.049972 -19.800062 180)
			(size 0.450088 0.450088)
			(layers "F.Cu" "F.Mask" "F.Paste")
			(net "GND")
		)
		(pad "AB74" smd circle
			(at 33.990026 -19.800062 180)
			(size 0.450088 0.450088)
			(layers "F.Cu" "F.Mask" "F.Paste")
			(net "M_A_CPU1_SA_DQ<22>")
		)
		(pad "AC1" smd circle
			(at -34.159952 -18.990056 180)
			(size 0.450088 0.450088)
			(layers "F.Cu" "F.Mask" "F.Paste")
			(net "GND")
		)
		(pad "AC2" smd circle
			(at -33.219898 -18.990056 180)
			(size 0.450088 0.450088)
			(layers "F.Cu" "F.Mask" "F.Paste")
			(net "M_G_CPU1_SA_DQ<24>")
		)
		(pad "AC3" smd circle
			(at -32.280098 -18.990056 180)
			(size 0.450088 0.450088)
			(layers "F.Cu" "F.Mask" "F.Paste")
			(net "M_G_CPU1_SA_DQ<23>")
		)
		(pad "AC4" smd circle
			(at -31.340044 -18.990056 180)
			(size 0.450088 0.450088)
			(layers "F.Cu" "F.Mask" "F.Paste")
			(net "PVDDCR_SOC_P1")
		)
		(pad "AC5" smd circle
			(at -30.39999 -18.990056 180)
			(size 0.450088 0.450088)
			(layers "F.Cu" "F.Mask" "F.Paste")
			(net "M_K_CPU1_SA_DQ<24>")
		)
		(pad "AC6" smd circle
			(at -29.459936 -18.990056 180)
			(size 0.450088 0.450088)
			(layers "F.Cu" "F.Mask" "F.Paste")
			(net "GND")
		)
		(pad "AC7" smd circle
			(at -28.519882 -18.990056 180)
			(size 0.450088 0.450088)
			(layers "F.Cu" "F.Mask" "F.Paste")
			(net "M_K_CPU1_SA_DQ<23>")
		)
		(pad "AC8" smd circle
			(at -27.580082 -18.990056 180)
			(size 0.450088 0.450088)
			(layers "F.Cu" "F.Mask" "F.Paste")
			(net "GND")
		)
		(pad "AC9" smd circle
			(at -26.640028 -18.990056 180)
			(size 0.450088 0.450088)
			(layers "F.Cu" "F.Mask" "F.Paste")
			(net "M_L_CPU1_SA_DQ<24>")
		)
		(pad "AC10" smd circle
			(at -25.699974 -18.990056 180)
			(size 0.450088 0.450088)
			(layers "F.Cu" "F.Mask" "F.Paste")
			(net "M_L_CPU1_SA_DQ<23>")
		)
		(pad "AC11" smd circle
			(at -24.75992 -18.990056 180)
			(size 0.450088 0.450088)
			(layers "F.Cu" "F.Mask" "F.Paste")
			(net "PVDDCR_SOC_P1")
		)
		(pad "AC12" smd circle
			(at -23.82012 -18.990056 180)
			(size 0.450088 0.450088)
			(layers "F.Cu" "F.Mask" "F.Paste")
			(net "M_H_CPU1_SA_DQ<24>")
		)
	)
)
